# T6G (Grand Teton) — schematic netlist excerpt (pin names and nets, part order shuffled) for the footprints in the layout excerpt that follows; sources: Cadence DE-HDL packaged netlist, KiCad conversion of 04192023_DAF0TMB3IC0_F0TG_MB_C_brd_V02_OCP.brd

R591  Q_RES  0 5% CHIP  pkg 0402LF  page 135 : A = P12V_OCP_SFF_BUF_EN_R ; B = P12V_OCP_EN_1_R2
C943  Q_CAP_DIFFBUS  DIFF BUS_0.22UF 6.3V 20% X6S  pkg C0201  page 63 : \1\ = P5E_CPU0_P1_TX_C_DP<11> ; \2\ = P5E_CPU0_P1_TX_DP<11>
R6287  Q_RES  1K 1% CHIP  pkg 0402LF  page 178 : A = P3V3_AUX ; B = USB_HUB2_TI_PWRCTL_POL

(kicad_pcb
	(version 20260206)
	(generator "pcbnew")
	(generator_version "10.0")
	(general
		(thickness 1.6)
		(legacy_teardrops no)
	)
	(paper "A4")
	(title_block
		(title "04192023_DAF0TMB3IC0_F0TG_MB_C_brd_V02_OCP.brd")
		(comment 1 "Grand Teton / footprints 4406-4408 of 8354")
	)
	(layers
		(0 "F.Cu" signal "TOP")
		(4 "In1.Cu" signal "GND")
		(6 "In2.Cu" signal "IN1")
		(8 "In3.Cu" signal "GND1")
		(10 "In4.Cu" signal "IN2")
		(12 "In5.Cu" signal "GND2")
		(14 "In6.Cu" signal "IN3")
		(16 "In7.Cu" signal "GND3")
		(18 "In8.Cu" signal "VCC")
		(20 "In9.Cu" signal "VCC1")
		(22 "In10.Cu" signal "GND4")
		(24 "In11.Cu" signal "IN4")
		(26 "In12.Cu" signal "GND5")
		(28 "In13.Cu" signal "IN5")
		(30 "In14.Cu" signal "GND6")
		(32 "In15.Cu" signal "IN6")
		(34 "In16.Cu" signal "GND7")
		(2 "B.Cu" signal "BOTTOM")
		(9 "F.Adhes" user "F.Adhesive")
		(11 "B.Adhes" user "B.Adhesive")
		(13 "F.Paste" user "Package Geometry/Pastemask Top")
		(15 "B.Paste" user "Package Geometry/Pastemask Bottom")
		(5 "F.SilkS" user "Ref Des/Silkscreen Top")
		(7 "B.SilkS" user "Ref Des/Silkscreen Bottom")
		(1 "F.Mask" user "Board Geometry/Soldermask Top")
		(3 "B.Mask" user "Board Geometry/Soldermask Bottom")
		(17 "Dwgs.User" user "User.Drawings")
		(19 "Cmts.User" user "User.Comments")
		(21 "Eco1.User" user "User.Eco1")
		(23 "Eco2.User" user "User.Eco2")
		(25 "Edge.Cuts" user "Board Geometry/Outline")
		(27 "Margin" user)
		(31 "F.CrtYd" user "Package Geometry/Place Bound Top")
		(29 "B.CrtYd" user "Package Geometry/Place Bound Bottom")
		(35 "F.Fab" user "Ref Des/Assembly Top")
		(33 "B.Fab" user "Ref Des/Assembly Bottom")
	)
	(footprint ""
		(layer "F.Cu")
		(at 446.359788 -32.174434 -90)
		(property "Reference" "R591"
			(at 0 0 270)
			(layer "F.SilkS")
			(hide yes)
			(effects
				(font
					(size 1.27 1.27)
				)
			)
		)
		(property "Value" ""
			(at 0 0 270)
			(layer "F.Fab")
			(effects
				(font
					(size 1.27 1.27)
				)
			)
		)
		(duplicate_pad_numbers_are_jumpers no)
		(fp_line
			(start -0.7874 0.4064)
			(end -0.7874 -0.4064)
			(stroke
				(width 0.1524)
				(type default)
			)
			(layer "F.SilkS")
		)
		(fp_line
			(start 0.7874 0.4064)
			(end -0.7874 0.4064)
			(stroke
				(width 0.1524)
				(type default)
			)
			(layer "F.SilkS")
		)
		(fp_line
			(start -0.7874 -0.4064)
			(end 0.7874 -0.4064)
			(stroke
				(width 0.1524)
				(type default)
			)
			(layer "F.SilkS")
		)
		(fp_line
			(start 0.7874 -0.4064)
			(end 0.7874 0.4064)
			(stroke
				(width 0.1524)
				(type default)
			)
			(layer "F.SilkS")
		)
		(fp_line
			(start -0.67945 0.3048)
			(end -0.67945 -0.305054)
			(stroke
				(width 0.1)
				(type default)
			)
			(layer "F.Fab")
		)
		(fp_line
			(start -0.12065 0.3048)
			(end -0.67945 0.3048)
			(stroke
				(width 0.1)
				(type default)
			)
			(layer "F.Fab")
		)
		(fp_line
			(start 0.120396 0.3048)
			(end 0.120396 0.2794)
			(stroke
				(width 0.1)
				(type default)
			)
			(layer "F.Fab")
		)
		(fp_line
			(start 0.67945 0.3048)
			(end 0.120396 0.3048)
			(stroke
				(width 0.1)
				(type default)
			)
			(layer "F.Fab")
		)
		(fp_line
			(start -0.12065 0.2794)
			(end -0.12065 0.3048)
			(stroke
				(width 0.1)
				(type default)
			)
			(layer "F.Fab")
		)
		(fp_line
			(start 0.120396 0.2794)
			(end -0.12065 0.2794)
			(stroke
				(width 0.1)
				(type default)
			)
			(layer "F.Fab")
		)
		(fp_line
			(start -0.12065 -0.2794)
			(end 0.12065 -0.2794)
			(stroke
				(width 0.1)
				(type default)
			)
			(layer "F.Fab")
		)
		(fp_line
			(start 0.12065 -0.2794)
			(end 0.12065 -0.3048)
			(stroke
				(width 0.1)
				(type default)
			)
			(layer "F.Fab")
		)
		(fp_line
			(start 0.12065 -0.3048)
			(end 0.67945 -0.3048)
			(stroke
				(width 0.1)
				(type default)
			)
			(layer "F.Fab")
		)
		(fp_line
			(start 0.67945 -0.3048)
			(end 0.67945 0.3048)
			(stroke
				(width 0.1)
				(type default)
			)
			(layer "F.Fab")
		)
		(fp_line
			(start -0.67945 -0.305054)
			(end -0.12065 -0.305054)
			(stroke
				(width 0.1)
				(type default)
			)
			(layer "F.Fab")
		)
		(fp_line
			(start -0.12065 -0.305054)
			(end -0.12065 -0.2794)
			(stroke
				(width 0.1)
				(type default)
			)
			(layer "F.Fab")
		)
		(pad "1" smd circle
			(at -0.40005 0 270)
			(size 0 0)
			(layers "F.Cu" "F.Mask" "F.Paste")
			(net "P12V_OCP_SFF_BUF_EN_R")
		)
		(pad "2" smd circle
			(at 0.40005 0 270)
			(size 0 0)
			(layers "F.Cu" "F.Mask" "F.Paste")
			(net "P12V_OCP_EN_1_R2")
		)
	)
	(footprint ""
		(layer "F.Cu")
		(at 351.938844 -381.41783 -90)
		(property "Reference" "C943"
			(at 0 0 270)
			(layer "F.SilkS")
			(hide yes)
			(effects
				(font
					(size 1.27 1.27)
				)
			)
		)
		(property "Value" ""
			(at 0 0 270)
			(layer "F.Fab")
			(effects
				(font
					(size 1.27 1.27)
				)
			)
		)
		(duplicate_pad_numbers_are_jumpers no)
		(fp_line
			(start -0.299974 0.150114)
			(end -0.299974 -0.150114)
			(stroke
				(width 0.1)
				(type default)
			)
			(layer "F.Fab")
		)
		(fp_line
			(start 0.299974 0.150114)
			(end -0.299974 0.150114)
			(stroke
				(width 0.1)
				(type default)
			)
			(layer "F.Fab")
		)
		(fp_line
			(start -0.299974 -0.150114)
			(end 0.299974 -0.150114)
			(stroke
				(width 0.1)
				(type default)
			)
			(layer "F.Fab")
		)
		(fp_line
			(start 0.299974 -0.150114)
			(end 0.299974 0.150114)
			(stroke
				(width 0.1)
				(type default)
			)
			(layer "F.Fab")
		)
		(pad "1" smd rect
			(at -0.2667 0 270)
			(size 0.3048 0.381)
			(layers "F.Cu" "F.Mask" "F.Paste")
			(net "P5E_CPU0_P1_TX_C_DP<11>")
		)
		(pad "2" smd rect
			(at 0.2667 0 270)
			(size 0.3048 0.381)
			(layers "F.Cu" "F.Mask" "F.Paste")
			(net "P5E_CPU0_P1_TX_DP<11>")
		)
	)
	(footprint ""
		(layer "F.Cu")
		(at 113.283238 -41.17975 -90)
		(property "Reference" "R6287"
			(at 0 0 270)
			(layer "F.SilkS")
			(hide yes)
			(effects
				(font
					(size 1.27 1.27)
				)
			)
		)
		(property "Value" ""
			(at 0 0 270)
			(layer "F.Fab")
			(effects
				(font
					(size 1.27 1.27)
				)
			)
		)
		(duplicate_pad_numbers_are_jumpers no)
		(fp_line
			(start -0.7874 0.4064)
			(end -0.7874 -0.4064)
			(stroke
				(width 0.1524)
				(type default)
			)
			(layer "F.SilkS")
		)
		(fp_line
			(start 0.7874 0.4064)
			(end -0.7874 0.4064)
			(stroke
				(width 0.1524)
				(type default)
			)
			(layer "F.SilkS")
		)
		(fp_line
			(start -0.7874 -0.4064)
			(end 0.7874 -0.4064)
			(stroke
				(width 0.1524)
				(type default)
			)
			(layer "F.SilkS")
		)
		(fp_line
			(start 0.7874 -0.4064)
			(end 0.7874 0.4064)
			(stroke
				(width 0.1524)
				(type default)
			)
			(layer "F.SilkS")
		)
		(fp_line
			(start -0.67945 0.3048)
			(end -0.67945 -0.305054)
			(stroke
				(width 0.1)
				(type default)
			)
			(layer "F.Fab")
		)
		(fp_line
			(start -0.12065 0.3048)
			(end -0.67945 0.3048)
			(stroke
				(width 0.1)
				(type default)
			)
			(layer "F.Fab")
		)
		(fp_line
			(start 0.120396 0.3048)
			(end 0.120396 0.2794)
			(stroke
				(width 0.1)
				(type default)
			)
			(layer "F.Fab")
		)
		(fp_line
			(start 0.67945 0.3048)
			(end 0.120396 0.3048)
			(stroke
				(width 0.1)
				(type default)
			)
			(layer "F.Fab")
		)
		(fp_line
			(start -0.12065 0.2794)
			(end -0.12065 0.3048)
			(stroke
				(width 0.1)
				(type default)
			)
			(layer "F.Fab")
		)
		(fp_line
			(start 0.120396 0.2794)
			(end -0.12065 0.2794)
			(stroke
				(width 0.1)
				(type default)
			)
			(layer "F.Fab")
		)
		(fp_line
			(start -0.12065 -0.2794)
			(end 0.12065 -0.2794)
			(stroke
				(width 0.1)
				(type default)
			)
			(layer "F.Fab")
		)
		(fp_line
			(start 0.12065 -0.2794)
			(end 0.12065 -0.3048)
			(stroke
				(width 0.1)
				(type default)
			)
			(layer "F.Fab")
		)
		(fp_line
			(start 0.12065 -0.3048)
			(end 0.67945 -0.3048)
			(stroke
				(width 0.1)
				(type default)
			)
			(layer "F.Fab")
		)
		(fp_line
			(start 0.67945 -0.3048)
			(end 0.67945 0.3048)
			(stroke
				(width 0.1)
				(type default)
			)
			(layer "F.Fab")
		)
		(fp_line
			(start -0.67945 -0.305054)
			(end -0.12065 -0.305054)
			(stroke
				(width 0.1)
				(type default)
			)
			(layer "F.Fab")
		)
		(fp_line
			(start -0.12065 -0.305054)
			(end -0.12065 -0.2794)
			(stroke
				(width 0.1)
				(type default)
			)
			(layer "F.Fab")
		)
		(pad "1" smd circle
			(at -0.40005 0 270)
			(size 0 0)
			(layers "F.Cu" "F.Mask" "F.Paste")
			(net "P3V3_AUX")
		)
		(pad "2" smd circle
			(at 0.40005 0 270)
			(size 0 0)
			(layers "F.Cu" "F.Mask" "F.Paste")
			(net "USB_HUB2_TI_PWRCTL_POL")
		)
	)
)
